# BASEBOARD_FAB2 (Tioga Pass) — schematic netlist excerpt (pin names and nets, part order shuffled) for the footprints in the layout excerpt that follows; sources: Cadence DE-HDL packaged netlist, KiCad conversion of Wiwynn_Tioga_Pass_MB.brd

R2T19  RES  200.0 1% CHIP  pkg 0402  page 93 : A = PVCCIO_CPU0 ; B = H_CPU_ERR0_GTL_R_N
R7D39  RES  0.0 5% CHIP  pkg 0402  page 104 : A = FM_CPU0_VRM_OSC_EN ; B = FM_CPU0_VRM_322M_156M_OSC_EN
C7P18  CAP  47UF 4V 20% X6S  pkg 0805  page 76 : A = PVCCIO_CPU1 ; B = GND

(kicad_pcb
	(version 20260206)
	(generator "pcbnew")
	(generator_version "10.0")
	(general
		(thickness 1.6)
		(legacy_teardrops no)
	)
	(paper "A4")
	(title_block
		(title "Wiwynn_Tioga_Pass_MB.brd")
		(comment 1 "Tioga Pass / footprints 3264-3266 of 4770")
	)
	(layers
		(0 "F.Cu" signal "TOP")
		(4 "In1.Cu" signal "L2GND")
		(6 "In2.Cu" signal "L3")
		(8 "In3.Cu" signal "L4GND")
		(10 "In4.Cu" signal "L5")
		(12 "In5.Cu" signal "L6GND")
		(14 "In6.Cu" signal "L7VCC")
		(16 "In7.Cu" signal "L8VCC")
		(18 "In8.Cu" signal "L9GND")
		(20 "In9.Cu" signal "L10")
		(22 "In10.Cu" signal "L11GND")
		(24 "In11.Cu" signal "L12")
		(26 "In12.Cu" signal "L13GND")
		(2 "B.Cu" signal "BOTTOM")
		(9 "F.Adhes" user "F.Adhesive")
		(11 "B.Adhes" user "B.Adhesive")
		(13 "F.Paste" user "Package Geometry/Pastemask Top")
		(15 "B.Paste" user "Package Geometry/Pastemask Bottom")
		(5 "F.SilkS" user "Ref Des/Silkscreen Top")
		(7 "B.SilkS" user "Ref Des/Silkscreen Bottom")
		(1 "F.Mask" user "Board Geometry/Soldermask Top")
		(3 "B.Mask" user "Board Geometry/Soldermask Bottom")
		(17 "Dwgs.User" user "User.Drawings")
		(19 "Cmts.User" user "User.Comments")
		(21 "Eco1.User" user "User.Eco1")
		(23 "Eco2.User" user "User.Eco2")
		(25 "Edge.Cuts" user "Board Geometry/Outline")
		(27 "Margin" user)
		(31 "F.CrtYd" user "Package Geometry/Place Bound Top")
		(29 "B.CrtYd" user "Package Geometry/Place Bound Bottom")
		(35 "F.Fab" user "Ref Des/Assembly Top")
		(33 "B.Fab" user "Ref Des/Assembly Bottom")
	)
	(footprint ""
		(layer "B.Cu")
		(at 374.325642 -39.874952 -90)
		(property "Reference" "R2T19"
			(at 0 0 90)
			(layer "B.SilkS")
			(hide yes)
			(effects
				(font
					(size 1.27 1.27)
				)
				(justify mirror)
			)
		)
		(property "Value" ""
			(at 0 0 90)
			(layer "B.Fab")
			(effects
				(font
					(size 1.27 1.27)
				)
				(justify mirror)
			)
		)
		(duplicate_pad_numbers_are_jumpers no)
		(fp_poly
			(pts
				(xy 0.2794 -0.1016) (xy -0.2794 -0.1016) (xy -0.2794 0.9906) (xy 0.2794 0.9906)
			)
			(stroke
				(width 0)
				(type default)
			)
			(fill no)
			(layer "B.CrtYd")
		)
		(fp_line
			(start -0.2794 0.9906)
			(end -0.2794 -0.1016)
			(stroke
				(width 0.1)
				(type default)
			)
			(layer "B.Fab")
		)
		(fp_line
			(start 0.2794 0.9906)
			(end -0.2794 0.9906)
			(stroke
				(width 0.1)
				(type default)
			)
			(layer "B.Fab")
		)
		(fp_line
			(start -0.2794 -0.1016)
			(end 0.2794 -0.1016)
			(stroke
				(width 0.1)
				(type default)
			)
			(layer "B.Fab")
		)
		(fp_line
			(start 0.2794 -0.1016)
			(end 0.2794 0.9906)
			(stroke
				(width 0.1)
				(type default)
			)
			(layer "B.Fab")
		)
		(pad "1" smd rect
			(at 0 0 90)
			(size 0.508 0.508)
			(layers "B.Cu" "B.Mask" "B.Paste")
			(net "PVCCIO_CPU0")
		)
		(pad "2" smd rect
			(at 0 0.889 90)
			(size 0.508 0.508)
			(layers "B.Cu" "B.Mask" "B.Paste")
			(net "H_CPU_ERR0_GTL_R_N")
		)
		(zone
			(layer "B.Cu")
			(hatch none 0.5)
			(connect_pads
				(clearance 0)
			)
			(min_thickness 0.25)
			(keepout
				(tracks not_allowed)
				(vias allowed)
				(pads allowed)
				(copperpour not_allowed)
				(footprints allowed)
			)
			(placement
				(enabled no)
				(sheetname "")
			)
			(fill
				(thermal_gap 0.5)
				(thermal_bridge_width 0.5)
				(island_removal_mode 0)
			)
			(polygon
				(pts
					(xy 373.690642 -39.620952) (xy 373.690642 -40.128952) (xy 374.071642 -40.128952) (xy 374.071642 -39.620952)
				)
			)
		)
		(zone
			(layer "B.Cu")
			(hatch none 0.5)
			(connect_pads
				(clearance 0)
			)
			(min_thickness 0.25)
			(keepout
				(tracks allowed)
				(vias not_allowed)
				(pads allowed)
				(copperpour not_allowed)
				(footprints allowed)
			)
			(placement
				(enabled no)
				(sheetname "")
			)
			(fill
				(thermal_gap 0.5)
				(thermal_bridge_width 0.5)
				(island_removal_mode 0)
			)
			(polygon
				(pts
					(xy 374.071642 -39.620952) (xy 374.071642 -40.128952) (xy 373.690642 -40.128952) (xy 373.690642 -39.620952)
				)
			)
		)
	)
	(footprint ""
		(layer "B.Cu")
		(at 352.8949 -72.0344 -90)
		(property "Reference" "R7D39"
			(at 0 0 90)
			(layer "B.SilkS")
			(hide yes)
			(effects
				(font
					(size 1.27 1.27)
				)
				(justify mirror)
			)
		)
		(property "Value" ""
			(at 0 0 90)
			(layer "B.Fab")
			(effects
				(font
					(size 1.27 1.27)
				)
				(justify mirror)
			)
		)
		(duplicate_pad_numbers_are_jumpers no)
		(fp_poly
			(pts
				(xy 0.2794 -0.1016) (xy -0.2794 -0.1016) (xy -0.2794 0.9906) (xy 0.2794 0.9906)
			)
			(stroke
				(width 0)
				(type default)
			)
			(fill no)
			(layer "B.CrtYd")
		)
		(fp_line
			(start -0.2794 0.9906)
			(end -0.2794 -0.1016)
			(stroke
				(width 0.1)
				(type default)
			)
			(layer "B.Fab")
		)
		(fp_line
			(start 0.2794 0.9906)
			(end -0.2794 0.9906)
			(stroke
				(width 0.1)
				(type default)
			)
			(layer "B.Fab")
		)
		(fp_line
			(start -0.2794 -0.1016)
			(end 0.2794 -0.1016)
			(stroke
				(width 0.1)
				(type default)
			)
			(layer "B.Fab")
		)
		(fp_line
			(start 0.2794 -0.1016)
			(end 0.2794 0.9906)
			(stroke
				(width 0.1)
				(type default)
			)
			(layer "B.Fab")
		)
		(pad "1" smd rect
			(at 0 0 90)
			(size 0.508 0.508)
			(layers "B.Cu" "B.Mask" "B.Paste")
			(net "FM_CPU0_VRM_OSC_EN")
		)
		(pad "2" smd rect
			(at 0 0.889 90)
			(size 0.508 0.508)
			(layers "B.Cu" "B.Mask" "B.Paste")
			(net "FM_CPU0_VRM_322M_156M_OSC_EN")
		)
		(zone
			(layer "B.Cu")
			(hatch none 0.5)
			(connect_pads
				(clearance 0)
			)
			(min_thickness 0.25)
			(keepout
				(tracks not_allowed)
				(vias allowed)
				(pads allowed)
				(copperpour not_allowed)
				(footprints allowed)
			)
			(placement
				(enabled no)
				(sheetname "")
			)
			(fill
				(thermal_gap 0.5)
				(thermal_bridge_width 0.5)
				(island_removal_mode 0)
			)
			(polygon
				(pts
					(xy 352.2599 -71.7804) (xy 352.2599 -72.2884) (xy 352.6409 -72.2884) (xy 352.6409 -71.7804)
				)
			)
		)
		(zone
			(layer "B.Cu")
			(hatch none 0.5)
			(connect_pads
				(clearance 0)
			)
			(min_thickness 0.25)
			(keepout
				(tracks allowed)
				(vias not_allowed)
				(pads allowed)
				(copperpour not_allowed)
				(footprints allowed)
			)
			(placement
				(enabled no)
				(sheetname "")
			)
			(fill
				(thermal_gap 0.5)
				(thermal_bridge_width 0.5)
				(island_removal_mode 0)
			)
			(polygon
				(pts
					(xy 352.6409 -71.7804) (xy 352.6409 -72.2884) (xy 352.2599 -72.2884) (xy 352.2599 -71.7804)
				)
			)
		)
	)
	(footprint ""
		(layer "B.Cu")
		(at 113.575592 -69.809614 -90)
		(property "Reference" "C7P18"
			(at 0 0 90)
			(layer "B.SilkS")
			(hide yes)
			(effects
				(font
					(size 1.27 1.27)
				)
				(justify mirror)
			)
		)
		(property "Value" ""
			(at 0 0 90)
			(layer "B.Fab")
			(effects
				(font
					(size 1.27 1.27)
				)
				(justify mirror)
			)
		)
		(duplicate_pad_numbers_are_jumpers no)
		(fp_poly
			(pts
				(xy 0.7239 -0.2159) (xy -0.7239 -0.2159) (xy -0.7239 1.9939) (xy 0.7239 1.9939)
			)
			(stroke
				(width 0)
				(type default)
			)
			(fill no)
			(layer "B.CrtYd")
		)
		(fp_line
			(start -0.7239 1.9939)
			(end -0.7239 -0.2159)
			(stroke
				(width 0.1)
				(type default)
			)
			(layer "B.Fab")
		)
		(fp_line
			(start 0.7239 1.9939)
			(end -0.7239 1.9939)
			(stroke
				(width 0.1)
				(type default)
			)
			(layer "B.Fab")
		)
		(fp_line
			(start -0.7239 -0.2159)
			(end 0.7239 -0.2159)
			(stroke
				(width 0.1)
				(type default)
			)
			(layer "B.Fab")
		)
		(fp_line
			(start 0.7239 -0.2159)
			(end 0.7239 1.9939)
			(stroke
				(width 0.1)
				(type default)
			)
			(layer "B.Fab")
		)
		(pad "1" smd rect
			(at 0 0 90)
			(size 1.27 1.016)
			(layers "B.Cu" "B.Mask" "B.Paste")
			(net "PVCCIO_CPU1")
		)
		(pad "2" smd rect
			(at 0 1.778 90)
			(size 1.27 1.016)
			(layers "B.Cu" "B.Mask" "B.Paste")
			(net "GND")
		)
		(zone
			(layer "B.Cu")
			(hatch none 0.5)
			(connect_pads
				(clearance 0)
			)
			(min_thickness 0.25)
			(keepout
				(tracks not_allowed)
				(vias allowed)
				(pads allowed)
				(copperpour not_allowed)
				(footprints allowed)
			)
			(placement
				(enabled no)
				(sheetname "")
			)
			(fill
				(thermal_gap 0.5)
				(thermal_bridge_width 0.5)
				(island_removal_mode 0)
			)
			(polygon
				(pts
					(xy 113.067592 -69.174614) (xy 113.067592 -70.444614) (xy 112.305592 -70.444614) (xy 112.305592 -69.174614)
				)
			)
		)
	)
)
